(kicad_pcb
	(version 20260206)
	(generator "pcbnew")
	(generator_version "10.0")
	(general
		(thickness 1.6)
		(legacy_teardrops no)
	)
	(paper "A4")
	(title_block
		(title "01162023_DA0F0TEBIF0_F0T_Expander_BD_F_brd_V02_OCP.brd")
		(comment 1 "Grand Teton / footprints 1735-1741 of 9728")
	)
	(layers
		(0 "F.Cu" signal "TOP")
		(4 "In1.Cu" signal "GND")
		(6 "In2.Cu" signal "VCC")
		(8 "In3.Cu" signal "VCC1")
		(10 "In4.Cu" signal "GND1")
		(12 "In5.Cu" signal "IN1")
		(14 "In6.Cu" signal "GND2")
		(16 "In7.Cu" signal "IN2")
		(18 "In8.Cu" signal "GND3")
		(20 "In9.Cu" signal "IN3")
		(22 "In10.Cu" signal "GND4")
		(24 "In11.Cu" signal "IN4")
		(26 "In12.Cu" signal "GND5")
		(28 "In13.Cu" signal "IN5")
		(30 "In14.Cu" signal "GND6")
		(32 "In15.Cu" signal "IN6")
		(34 "In16.Cu" signal "GND7")
		(2 "B.Cu" signal "BOTTOM")
		(9 "F.Adhes" user "F.Adhesive")
		(11 "B.Adhes" user "B.Adhesive")
		(13 "F.Paste" user "Package Geometry/Pastemask Top")
		(15 "B.Paste" user "Package Geometry/Pastemask Bottom")
		(5 "F.SilkS" user "Ref Des/Silkscreen Top")
		(7 "B.SilkS" user "Ref Des/Silkscreen Bottom")
		(1 "F.Mask" user "Board Geometry/Soldermask Top")
		(3 "B.Mask" user "Board Geometry/Soldermask Bottom")
		(17 "Dwgs.User" user "User.Drawings")
		(19 "Cmts.User" user "User.Comments")
		(21 "Eco1.User" user "User.Eco1")
		(23 "Eco2.User" user "User.Eco2")
		(25 "Edge.Cuts" user "Board Geometry/Outline")
		(27 "Margin" user)
		(31 "F.CrtYd" user "Package Geometry/Place Bound Top")
		(29 "B.CrtYd" user "Package Geometry/Place Bound Bottom")
		(35 "F.Fab" user "Ref Des/Assembly Top")
		(33 "B.Fab" user "Ref Des/Assembly Bottom")
	)
	(footprint ""
		(layer "F.Cu")
		(at 258.54533 -191.654684)
		(property "Reference" "R4901"
			(at 0 0 0)
			(layer "F.SilkS")
			(hide yes)
			(effects
				(font
					(size 1.27 1.27)
				)
			)
		)
		(property "Value" ""
			(at 0 0 0)
			(layer "F.Fab")
			(effects
				(font
					(size 1.27 1.27)
				)
			)
		)
		(duplicate_pad_numbers_are_jumpers no)
		(fp_line
			(start -0.7874 -0.4064)
			(end 0.7874 -0.4064)
			(stroke
				(width 0.1524)
				(type default)
			)
			(layer "F.SilkS")
		)
		(fp_line
			(start -0.7874 0.4064)
			(end -0.7874 -0.4064)
			(stroke
				(width 0.1524)
				(type default)
			)
			(layer "F.SilkS")
		)
		(fp_line
			(start 0.7874 -0.4064)
			(end 0.7874 0.4064)
			(stroke
				(width 0.1524)
				(type default)
			)
			(layer "F.SilkS")
		)
		(fp_line
			(start 0.7874 0.4064)
			(end -0.7874 0.4064)
			(stroke
				(width 0.1524)
				(type default)
			)
			(layer "F.SilkS")
		)
		(fp_line
			(start -0.67945 -0.305054)
			(end -0.12065 -0.305054)
			(stroke
				(width 0.1)
				(type default)
			)
			(layer "F.Fab")
		)
		(fp_line
			(start -0.67945 0.3048)
			(end -0.67945 -0.305054)
			(stroke
				(width 0.1)
				(type default)
			)
			(layer "F.Fab")
		)
		(fp_line
			(start -0.12065 -0.305054)
			(end -0.12065 -0.2794)
			(stroke
				(width 0.1)
				(type default)
			)
			(layer "F.Fab")
		)
		(fp_line
			(start -0.12065 -0.2794)
			(end 0.12065 -0.2794)
			(stroke
				(width 0.1)
				(type default)
			)
			(layer "F.Fab")
		)
		(fp_line
			(start -0.12065 0.2794)
			(end -0.12065 0.3048)
			(stroke
				(width 0.1)
				(type default)
			)
			(layer "F.Fab")
		)
		(fp_line
			(start -0.12065 0.3048)
			(end -0.67945 0.3048)
			(stroke
				(width 0.1)
				(type default)
			)
			(layer "F.Fab")
		)
		(fp_line
			(start 0.120396 0.2794)
			(end -0.12065 0.2794)
			(stroke
				(width 0.1)
				(type default)
			)
			(layer "F.Fab")
		)
		(fp_line
			(start 0.120396 0.3048)
			(end 0.120396 0.2794)
			(stroke
				(width 0.1)
				(type default)
			)
			(layer "F.Fab")
		)
		(fp_line
			(start 0.12065 -0.3048)
			(end 0.67945 -0.3048)
			(stroke
				(width 0.1)
				(type default)
			)
			(layer "F.Fab")
		)
		(fp_line
			(start 0.12065 -0.2794)
			(end 0.12065 -0.3048)
			(stroke
				(width 0.1)
				(type default)
			)
			(layer "F.Fab")
		)
		(fp_line
			(start 0.67945 -0.3048)
			(end 0.67945 0.3048)
			(stroke
				(width 0.1)
				(type default)
			)
			(layer "F.Fab")
		)
		(fp_line
			(start 0.67945 0.3048)
			(end 0.120396 0.3048)
			(stroke
				(width 0.1)
				(type default)
			)
			(layer "F.Fab")
		)
		(pad "1" smd circle
			(at -0.40005 0)
			(size 0 0)
			(layers "F.Cu" "F.Mask" "F.Paste")
			(net "JTAG_FPGA_TCK")
		)
		(pad "2" smd circle
			(at 0.40005 0)
			(size 0 0)
			(layers "F.Cu" "F.Mask" "F.Paste")
			(net "JTAG_CONN_TCK")
		)
	)
	(footprint ""
		(layer "F.Cu")
		(at 20.48764 -25.342342 -90)
		(property "Reference" "R411"
			(at 0 0 270)
			(layer "F.SilkS")
			(hide yes)
			(effects
				(font
					(size 1.27 1.27)
				)
			)
		)
		(property "Value" ""
			(at 0 0 270)
			(layer "F.Fab")
			(effects
				(font
					(size 1.27 1.27)
				)
			)
		)
		(duplicate_pad_numbers_are_jumpers no)
		(fp_line
			(start -0.7874 0.4064)
			(end -0.7874 -0.4064)
			(stroke
				(width 0.1524)
				(type default)
			)
			(layer "F.SilkS")
		)
		(fp_line
			(start 0.7874 0.4064)
			(end -0.7874 0.4064)
			(stroke
				(width 0.1524)
				(type default)
			)
			(layer "F.SilkS")
		)
		(fp_line
			(start -0.7874 -0.4064)
			(end 0.7874 -0.4064)
			(stroke
				(width 0.1524)
				(type default)
			)
			(layer "F.SilkS")
		)
		(fp_line
			(start 0.7874 -0.4064)
			(end 0.7874 0.4064)
			(stroke
				(width 0.1524)
				(type default)
			)
			(layer "F.SilkS")
		)
		(fp_line
			(start -0.67945 0.3048)
			(end -0.67945 -0.305054)
			(stroke
				(width 0.1)
				(type default)
			)
			(layer "F.Fab")
		)
		(fp_line
			(start -0.12065 0.3048)
			(end -0.67945 0.3048)
			(stroke
				(width 0.1)
				(type default)
			)
			(layer "F.Fab")
		)
		(fp_line
			(start 0.120396 0.3048)
			(end 0.120396 0.2794)
			(stroke
				(width 0.1)
				(type default)
			)
			(layer "F.Fab")
		)
		(fp_line
			(start 0.67945 0.3048)
			(end 0.120396 0.3048)
			(stroke
				(width 0.1)
				(type default)
			)
			(layer "F.Fab")
		)
		(fp_line
			(start -0.12065 0.2794)
			(end -0.12065 0.3048)
			(stroke
				(width 0.1)
				(type default)
			)
			(layer "F.Fab")
		)
		(fp_line
			(start 0.120396 0.2794)
			(end -0.12065 0.2794)
			(stroke
				(width 0.1)
				(type default)
			)
			(layer "F.Fab")
		)
		(fp_line
			(start -0.12065 -0.2794)
			(end 0.12065 -0.2794)
			(stroke
				(width 0.1)
				(type default)
			)
			(layer "F.Fab")
		)
		(fp_line
			(start 0.12065 -0.2794)
			(end 0.12065 -0.3048)
			(stroke
				(width 0.1)
				(type default)
			)
			(layer "F.Fab")
		)
		(fp_line
			(start 0.12065 -0.3048)
			(end 0.67945 -0.3048)
			(stroke
				(width 0.1)
				(type default)
			)
			(layer "F.Fab")
		)
		(fp_line
			(start 0.67945 -0.3048)
			(end 0.67945 0.3048)
			(stroke
				(width 0.1)
				(type default)
			)
			(layer "F.Fab")
		)
		(fp_line
			(start -0.67945 -0.305054)
			(end -0.12065 -0.305054)
			(stroke
				(width 0.1)
				(type default)
			)
			(layer "F.Fab")
		)
		(fp_line
			(start -0.12065 -0.305054)
			(end -0.12065 -0.2794)
			(stroke
				(width 0.1)
				(type default)
			)
			(layer "F.Fab")
		)
		(pad "1" smd circle
			(at -0.40005 0 270)
			(size 0 0)
			(layers "F.Cu" "F.Mask" "F.Paste")
			(net "GND")
		)
		(pad "2" smd circle
			(at 0.40005 0 270)
			(size 0 0)
			(layers "F.Cu" "F.Mask" "F.Paste")
			(net "DUALPORT_N_SSD0")
		)
	)
	(footprint ""
		(layer "F.Cu")
		(at 168.367202 -57.332626)
		(property "Reference" "R6836"
			(at 0 0 0)
			(layer "F.SilkS")
			(hide yes)
			(effects
				(font
					(size 1.27 1.27)
				)
			)
		)
		(property "Value" ""
			(at 0 0 0)
			(layer "F.Fab")
			(effects
				(font
					(size 1.27 1.27)
				)
			)
		)
		(duplicate_pad_numbers_are_jumpers no)
		(fp_line
			(start -0.7874 -0.4064)
			(end 0.7874 -0.4064)
			(stroke
				(width 0.1524)
				(type default)
			)
			(layer "F.SilkS")
		)
		(fp_line
			(start -0.7874 0.4064)
			(end -0.7874 -0.4064)
			(stroke
				(width 0.1524)
				(type default)
			)
			(layer "F.SilkS")
		)
		(fp_line
			(start 0.7874 -0.4064)
			(end 0.7874 0.4064)
			(stroke
				(width 0.1524)
				(type default)
			)
			(layer "F.SilkS")
		)
		(fp_line
			(start 0.7874 0.4064)
			(end -0.7874 0.4064)
			(stroke
				(width 0.1524)
				(type default)
			)
			(layer "F.SilkS")
		)
		(fp_line
			(start -0.67945 -0.305054)
			(end -0.12065 -0.305054)
			(stroke
				(width 0.1)
				(type default)
			)
			(layer "F.Fab")
		)
		(fp_line
			(start -0.67945 0.3048)
			(end -0.67945 -0.305054)
			(stroke
				(width 0.1)
				(type default)
			)
			(layer "F.Fab")
		)
		(fp_line
			(start -0.12065 -0.305054)
			(end -0.12065 -0.2794)
			(stroke
				(width 0.1)
				(type default)
			)
			(layer "F.Fab")
		)
		(fp_line
			(start -0.12065 -0.2794)
			(end 0.12065 -0.2794)
			(stroke
				(width 0.1)
				(type default)
			)
			(layer "F.Fab")
		)
		(fp_line
			(start -0.12065 0.2794)
			(end -0.12065 0.3048)
			(stroke
				(width 0.1)
				(type default)
			)
			(layer "F.Fab")
		)
		(fp_line
			(start -0.12065 0.3048)
			(end -0.67945 0.3048)
			(stroke
				(width 0.1)
				(type default)
			)
			(layer "F.Fab")
		)
		(fp_line
			(start 0.120396 0.2794)
			(end -0.12065 0.2794)
			(stroke
				(width 0.1)
				(type default)
			)
			(layer "F.Fab")
		)
		(fp_line
			(start 0.120396 0.3048)
			(end 0.120396 0.2794)
			(stroke
				(width 0.1)
				(type default)
			)
			(layer "F.Fab")
		)
		(fp_line
			(start 0.12065 -0.3048)
			(end 0.67945 -0.3048)
			(stroke
				(width 0.1)
				(type default)
			)
			(layer "F.Fab")
		)
		(fp_line
			(start 0.12065 -0.2794)
			(end 0.12065 -0.3048)
			(stroke
				(width 0.1)
				(type default)
			)
			(layer "F.Fab")
		)
		(fp_line
			(start 0.67945 -0.3048)
			(end 0.67945 0.3048)
			(stroke
				(width 0.1)
				(type default)
			)
			(layer "F.Fab")
		)
		(fp_line
			(start 0.67945 0.3048)
			(end 0.120396 0.3048)
			(stroke
				(width 0.1)
				(type default)
			)
			(layer "F.Fab")
		)
		(pad "1" smd circle
			(at -0.40005 0)
			(size 0 0)
			(layers "F.Cu" "F.Mask" "F.Paste")
			(net "SSD5_PWR_EN_R")
		)
		(pad "2" smd circle
			(at 0.40005 0)
			(size 0 0)
			(layers "F.Cu" "F.Mask" "F.Paste")
			(net "GND")
		)
	)
	(footprint ""
		(layer "F.Cu")
		(at 386.90804 -153.3144 180)
		(property "Reference" "R331"
			(at 0 0 180)
			(layer "F.SilkS")
			(hide yes)
			(effects
				(font
					(size 1.27 1.27)
				)
			)
		)
		(property "Value" ""
			(at 0 0 180)
			(layer "F.Fab")
			(effects
				(font
					(size 1.27 1.27)
				)
			)
		)
		(duplicate_pad_numbers_are_jumpers no)
		(fp_line
			(start 0.7874 0.4064)
			(end -0.7874 0.4064)
			(stroke
				(width 0.1524)
				(type default)
			)
			(layer "F.SilkS")
		)
		(fp_line
			(start 0.7874 -0.4064)
			(end 0.7874 0.4064)
			(stroke
				(width 0.1524)
				(type default)
			)
			(layer "F.SilkS")
		)
		(fp_line
			(start -0.7874 0.4064)
			(end -0.7874 -0.4064)
			(stroke
				(width 0.1524)
				(type default)
			)
			(layer "F.SilkS")
		)
		(fp_line
			(start -0.7874 -0.4064)
			(end 0.7874 -0.4064)
			(stroke
				(width 0.1524)
				(type default)
			)
			(layer "F.SilkS")
		)
		(fp_line
			(start 0.67945 0.3048)
			(end 0.120396 0.3048)
			(stroke
				(width 0.1)
				(type default)
			)
			(layer "F.Fab")
		)
		(fp_line
			(start 0.67945 -0.3048)
			(end 0.67945 0.3048)
			(stroke
				(width 0.1)
				(type default)
			)
			(layer "F.Fab")
		)
		(fp_line
			(start 0.12065 -0.2794)
			(end 0.12065 -0.3048)
			(stroke
				(width 0.1)
				(type default)
			)
			(layer "F.Fab")
		)
		(fp_line
			(start 0.12065 -0.3048)
			(end 0.67945 -0.3048)
			(stroke
				(width 0.1)
				(type default)
			)
			(layer "F.Fab")
		)
		(fp_line
			(start 0.120396 0.3048)
			(end 0.120396 0.2794)
			(stroke
				(width 0.1)
				(type default)
			)
			(layer "F.Fab")
		)
		(fp_line
			(start 0.120396 0.2794)
			(end -0.12065 0.2794)
			(stroke
				(width 0.1)
				(type default)
			)
			(layer "F.Fab")
		)
		(fp_line
			(start -0.12065 0.3048)
			(end -0.67945 0.3048)
			(stroke
				(width 0.1)
				(type default)
			)
			(layer "F.Fab")
		)
		(fp_line
			(start -0.12065 0.2794)
			(end -0.12065 0.3048)
			(stroke
				(width 0.1)
				(type default)
			)
			(layer "F.Fab")
		)
		(fp_line
			(start -0.12065 -0.2794)
			(end 0.12065 -0.2794)
			(stroke
				(width 0.1)
				(type default)
			)
			(layer "F.Fab")
		)
		(fp_line
			(start -0.12065 -0.305054)
			(end -0.12065 -0.2794)
			(stroke
				(width 0.1)
				(type default)
			)
			(layer "F.Fab")
		)
		(fp_line
			(start -0.67945 0.3048)
			(end -0.67945 -0.305054)
			(stroke
				(width 0.1)
				(type default)
			)
			(layer "F.Fab")
		)
		(fp_line
			(start -0.67945 -0.305054)
			(end -0.12065 -0.305054)
			(stroke
				(width 0.1)
				(type default)
			)
			(layer "F.Fab")
		)
		(pad "1" smd circle
			(at -0.40005 0 180)
			(size 0 0)
			(layers "F.Cu" "F.Mask" "F.Paste")
			(net "NIC6_SLOT_ID0")
		)
		(pad "2" smd circle
			(at 0.40005 0 180)
			(size 0 0)
			(layers "F.Cu" "F.Mask" "F.Paste")
			(net "P3V3_NIC6")
		)
	)
	(footprint ""
		(layer "F.Cu")
		(at 95.105728 -245.824248 180)
		(property "Reference" "R818"
			(at 0 0 180)
			(layer "F.SilkS")
			(hide yes)
			(effects
				(font
					(size 1.27 1.27)
				)
			)
		)
		(property "Value" ""
			(at 0 0 180)
			(layer "F.Fab")
			(effects
				(font
					(size 1.27 1.27)
				)
			)
		)
		(duplicate_pad_numbers_are_jumpers no)
		(fp_line
			(start 0.7874 0.4064)
			(end -0.7874 0.4064)
			(stroke
				(width 0.1524)
				(type default)
			)
			(layer "F.SilkS")
		)
		(fp_line
			(start 0.7874 -0.4064)
			(end 0.7874 0.4064)
			(stroke
				(width 0.1524)
				(type default)
			)
			(layer "F.SilkS")
		)
		(fp_line
			(start -0.7874 0.4064)
			(end -0.7874 -0.4064)
			(stroke
				(width 0.1524)
				(type default)
			)
			(layer "F.SilkS")
		)
		(fp_line
			(start -0.7874 -0.4064)
			(end 0.7874 -0.4064)
			(stroke
				(width 0.1524)
				(type default)
			)
			(layer "F.SilkS")
		)
		(fp_line
			(start 0.67945 0.3048)
			(end 0.120396 0.3048)
			(stroke
				(width 0.1)
				(type default)
			)
			(layer "F.Fab")
		)
		(fp_line
			(start 0.67945 -0.3048)
			(end 0.67945 0.3048)
			(stroke
				(width 0.1)
				(type default)
			)
			(layer "F.Fab")
		)
		(fp_line
			(start 0.12065 -0.2794)
			(end 0.12065 -0.3048)
			(stroke
				(width 0.1)
				(type default)
			)
			(layer "F.Fab")
		)
		(fp_line
			(start 0.12065 -0.3048)
			(end 0.67945 -0.3048)
			(stroke
				(width 0.1)
				(type default)
			)
			(layer "F.Fab")
		)
		(fp_line
			(start 0.120396 0.3048)
			(end 0.120396 0.2794)
			(stroke
				(width 0.1)
				(type default)
			)
			(layer "F.Fab")
		)
		(fp_line
			(start 0.120396 0.2794)
			(end -0.12065 0.2794)
			(stroke
				(width 0.1)
				(type default)
			)
			(layer "F.Fab")
		)
		(fp_line
			(start -0.12065 0.3048)
			(end -0.67945 0.3048)
			(stroke
				(width 0.1)
				(type default)
			)
			(layer "F.Fab")
		)
		(fp_line
			(start -0.12065 0.2794)
			(end -0.12065 0.3048)
			(stroke
				(width 0.1)
				(type default)
			)
			(layer "F.Fab")
		)
		(fp_line
			(start -0.12065 -0.2794)
			(end 0.12065 -0.2794)
			(stroke
				(width 0.1)
				(type default)
			)
			(layer "F.Fab")
		)
		(fp_line
			(start -0.12065 -0.305054)
			(end -0.12065 -0.2794)
			(stroke
				(width 0.1)
				(type default)
			)
			(layer "F.Fab")
		)
		(fp_line
			(start -0.67945 0.3048)
			(end -0.67945 -0.305054)
			(stroke
				(width 0.1)
				(type default)
			)
			(layer "F.Fab")
		)
		(fp_line
			(start -0.67945 -0.305054)
			(end -0.12065 -0.305054)
			(stroke
				(width 0.1)
				(type default)
			)
			(layer "F.Fab")
		)
		(pad "1" smd circle
			(at -0.40005 0 180)
			(size 0 0)
			(layers "F.Cu" "F.Mask" "F.Paste")
			(net "PEX_P1V8_ADC_A1")
		)
		(pad "2" smd circle
			(at 0.40005 0 180)
			(size 0 0)
			(layers "F.Cu" "F.Mask" "F.Paste")
			(net "GND")
		)
	)
	(footprint ""
		(layer "F.Cu")
		(at 25.524968 -356.244906 90)
		(property "Reference" "C2158"
			(at 0 0 90)
			(layer "F.SilkS")
			(hide yes)
			(effects
				(font
					(size 1.27 1.27)
				)
			)
		)
		(property "Value" ""
			(at 0 0 90)
			(layer "F.Fab")
			(effects
				(font
					(size 1.27 1.27)
				)
			)
		)
		(duplicate_pad_numbers_are_jumpers no)
		(fp_line
			(start 0.299974 -0.150114)
			(end 0.299974 0.150114)
			(stroke
				(width 0.1)
				(type default)
			)
			(layer "F.Fab")
		)
		(fp_line
			(start -0.299974 -0.150114)
			(end 0.299974 -0.150114)
			(stroke
				(width 0.1)
				(type default)
			)
			(layer "F.Fab")
		)
		(fp_line
			(start 0.299974 0.150114)
			(end -0.299974 0.150114)
			(stroke
				(width 0.1)
				(type default)
			)
			(layer "F.Fab")
		)
		(fp_line
			(start -0.299974 0.150114)
			(end -0.299974 -0.150114)
			(stroke
				(width 0.1)
				(type default)
			)
			(layer "F.Fab")
		)
		(pad "1" smd rect
			(at -0.2667 0 90)
			(size 0.3048 0.381)
			(layers "F.Cu" "F.Mask" "F.Paste")
			(net "P5E_PEX0_STN4_TX_DP<76>")
		)
		(pad "2" smd rect
			(at 0.2667 0 90)
			(size 0.3048 0.381)
			(layers "F.Cu" "F.Mask" "F.Paste")
			(net "P5E_PEX0_STN4_TX_C_DP<76>")
		)
	)
	(footprint ""
		(layer "F.Cu")
		(at 216.022936 -188.652404 90)
		(property "Reference" "R5414"
			(at 0 0 90)
			(layer "F.SilkS")
			(hide yes)
			(effects
				(font
					(size 1.27 1.27)
				)
			)
		)
		(property "Value" ""
			(at 0 0 90)
			(layer "F.Fab")
			(effects
				(font
					(size 1.27 1.27)
				)
			)
		)
		(duplicate_pad_numbers_are_jumpers no)
		(fp_line
			(start 0.7874 -0.4064)
			(end 0.7874 0.4064)
			(stroke
				(width 0.1524)
				(type default)
			)
			(layer "F.SilkS")
		)
		(fp_line
			(start -0.7874 -0.4064)
			(end 0.7874 -0.4064)
			(stroke
				(width 0.1524)
				(type default)
			)
			(layer "F.SilkS")
		)
		(fp_line
			(start 0.7874 0.4064)
			(end -0.7874 0.4064)
			(stroke
				(width 0.1524)
				(type default)
			)
			(layer "F.SilkS")
		)
		(fp_line
			(start -0.7874 0.4064)
			(end -0.7874 -0.4064)
			(stroke
				(width 0.1524)
				(type default)
			)
			(layer "F.SilkS")
		)
		(fp_line
			(start -0.12065 -0.305054)
			(end -0.12065 -0.2794)
			(stroke
				(width 0.1)
				(type default)
			)
			(layer "F.Fab")
		)
		(fp_line
			(start -0.67945 -0.305054)
			(end -0.12065 -0.305054)
			(stroke
				(width 0.1)
				(type default)
			)
			(layer "F.Fab")
		)
		(fp_line
			(start 0.67945 -0.3048)
			(end 0.67945 0.3048)
			(stroke
				(width 0.1)
				(type default)
			)
			(layer "F.Fab")
		)
		(fp_line
			(start 0.12065 -0.3048)
			(end 0.67945 -0.3048)
			(stroke
				(width 0.1)
				(type default)
			)
			(layer "F.Fab")
		)
		(fp_line
			(start 0.12065 -0.2794)
			(end 0.12065 -0.3048)
			(stroke
				(width 0.1)
				(type default)
			)
			(layer "F.Fab")
		)
		(fp_line
			(start -0.12065 -0.2794)
			(end 0.12065 -0.2794)
			(stroke
				(width 0.1)
				(type default)
			)
			(layer "F.Fab")
		)
		(fp_line
			(start 0.120396 0.2794)
			(end -0.12065 0.2794)
			(stroke
				(width 0.1)
				(type default)
			)
			(layer "F.Fab")
		)
		(fp_line
			(start -0.12065 0.2794)
			(end -0.12065 0.3048)
			(stroke
				(width 0.1)
				(type default)
			)
			(layer "F.Fab")
		)
		(fp_line
			(start 0.67945 0.3048)
			(end 0.120396 0.3048)
			(stroke
				(width 0.1)
				(type default)
			)
			(layer "F.Fab")
		)
		(fp_line
			(start 0.120396 0.3048)
			(end 0.120396 0.2794)
			(stroke
				(width 0.1)
				(type default)
			)
			(layer "F.Fab")
		)
		(fp_line
			(start -0.12065 0.3048)
			(end -0.67945 0.3048)
			(stroke
				(width 0.1)
				(type default)
			)
			(layer "F.Fab")
		)
		(fp_line
			(start -0.67945 0.3048)
			(end -0.67945 -0.305054)
			(stroke
				(width 0.1)
				(type default)
			)
			(layer "F.Fab")
		)
		(pad "1" smd circle
			(at -0.40005 0 90)
			(size 0 0)
			(layers "F.Cu" "F.Mask" "F.Paste")
			(net "BIC_SEL_FLASH_SW0_R")
		)
		(pad "2" smd circle
			(at 0.40005 0 90)
			(size 0 0)
			(layers "F.Cu" "F.Mask" "F.Paste")
			(net "GND")
		)
	)
)
